# BASEBOARD_FAB2 (Tioga Pass) — schematic netlist excerpt (pin names and nets, part order shuffled) for the footprints in the layout excerpt that follows; sources: Cadence DE-HDL packaged netlist, KiCad conversion of Wiwynn_Tioga_Pass_MB.brd

R4D16  RES  27.4 1% CHIP  pkg 0402  page 103 : A = CLK_100M_CPU1_PE_REFCLK_R_DN ; B = CLK_100M_CPU1_PE_REFCLK_DN
R6D6  RES  240 1.0% EMPTY  pkg 0402  page 90 : A = GND ; B = PD_CPU0_TXT_PLTEN
XRU2  SOCKET_P_MECH_A  PLASTIC  pkg RIGHT  page 55
C5D27  CAP_A  22.0UF 4V 20% X6S  pkg 0603V  page 42 : A = PVCCIN_CPU0 ; B = GND

(kicad_pcb
	(version 20260206)
	(generator "pcbnew")
	(generator_version "10.0")
	(general
		(thickness 1.6)
		(legacy_teardrops no)
	)
	(paper "A4")
	(title_block
		(title "Wiwynn_Tioga_Pass_MB.brd")
		(comment 1 "Tioga Pass / footprints 711-714 of 4770")
	)
	(layers
		(0 "F.Cu" signal "TOP")
		(4 "In1.Cu" signal "L2GND")
		(6 "In2.Cu" signal "L3")
		(8 "In3.Cu" signal "L4GND")
		(10 "In4.Cu" signal "L5")
		(12 "In5.Cu" signal "L6GND")
		(14 "In6.Cu" signal "L7VCC")
		(16 "In7.Cu" signal "L8VCC")
		(18 "In8.Cu" signal "L9GND")
		(20 "In9.Cu" signal "L10")
		(22 "In10.Cu" signal "L11GND")
		(24 "In11.Cu" signal "L12")
		(26 "In12.Cu" signal "L13GND")
		(2 "B.Cu" signal "BOTTOM")
		(9 "F.Adhes" user "F.Adhesive")
		(11 "B.Adhes" user "B.Adhesive")
		(13 "F.Paste" user "Package Geometry/Pastemask Top")
		(15 "B.Paste" user "Package Geometry/Pastemask Bottom")
		(5 "F.SilkS" user "Ref Des/Silkscreen Top")
		(7 "B.SilkS" user "Ref Des/Silkscreen Bottom")
		(1 "F.Mask" user "Board Geometry/Soldermask Top")
		(3 "B.Mask" user "Board Geometry/Soldermask Bottom")
		(17 "Dwgs.User" user "User.Drawings")
		(19 "Cmts.User" user "User.Comments")
		(21 "Eco1.User" user "User.Eco1")
		(23 "Eco2.User" user "User.Eco2")
		(25 "Edge.Cuts" user "Board Geometry/Outline")
		(27 "Margin" user)
		(31 "F.CrtYd" user "Package Geometry/Place Bound Top")
		(29 "B.CrtYd" user "Package Geometry/Place Bound Bottom")
		(35 "F.Fab" user "Ref Des/Assembly Top")
		(33 "B.Fab" user "Ref Des/Assembly Bottom")
	)
	(footprint ""
		(layer "F.Cu")
		(at 124.222002 -77.449934 180)
		(property "Reference" "XRU2"
			(at -17.763998 32.632396 0)
			(unlocked yes)
			(layer "F.SilkS")
			(effects
				(font
					(size 0.7874 0.5842)
					(thickness 0.1524)
				)
				(justify left)
			)
		)
		(property "Value" ""
			(at 0 0 180)
			(layer "F.Fab")
			(effects
				(font
					(size 1.27 1.27)
				)
			)
		)
		(duplicate_pad_numbers_are_jumpers no)
	)
	(footprint ""
		(layer "F.Cu")
		(at 281.178 -75.946 90)
		(property "Reference" "R6D6"
			(at 0 0 90)
			(layer "F.SilkS")
			(hide yes)
			(effects
				(font
					(size 1.27 1.27)
				)
			)
		)
		(property "Value" ""
			(at 0 0 90)
			(layer "F.Fab")
			(effects
				(font
					(size 1.27 1.27)
				)
			)
		)
		(duplicate_pad_numbers_are_jumpers no)
		(fp_rect
			(start -0.2794 -0.1016)
			(end 0.2794 0.9906)
			(stroke
				(width 0)
				(type default)
			)
			(fill no)
			(layer "F.CrtYd")
		)
		(fp_line
			(start 0.2794 -0.1016)
			(end -0.2794 -0.1016)
			(stroke
				(width 0.1)
				(type default)
			)
			(layer "F.Fab")
		)
		(fp_line
			(start -0.2794 -0.1016)
			(end -0.2794 0.9906)
			(stroke
				(width 0.1)
				(type default)
			)
			(layer "F.Fab")
		)
		(fp_line
			(start 0.2794 0.9906)
			(end 0.2794 -0.1016)
			(stroke
				(width 0.1)
				(type default)
			)
			(layer "F.Fab")
		)
		(fp_line
			(start -0.2794 0.9906)
			(end 0.2794 0.9906)
			(stroke
				(width 0.1)
				(type default)
			)
			(layer "F.Fab")
		)
		(pad "1" smd rect
			(at 0 0 90)
			(size 0.508 0.508)
			(layers "F.Cu" "F.Mask" "F.Paste")
			(net "GND")
		)
		(pad "2" smd rect
			(at 0 0.889 90)
			(size 0.508 0.508)
			(layers "F.Cu" "F.Mask" "F.Paste")
			(net "PD_CPU0_TXT_PLTEN")
		)
		(zone
			(layer "F.Cu")
			(hatch none 0.5)
			(connect_pads
				(clearance 0)
			)
			(min_thickness 0.25)
			(keepout
				(tracks allowed)
				(vias not_allowed)
				(pads allowed)
				(copperpour not_allowed)
				(footprints allowed)
			)
			(placement
				(enabled no)
				(sheetname "")
			)
			(fill
				(thermal_gap 0.5)
				(thermal_bridge_width 0.5)
				(island_removal_mode 0)
			)
			(polygon
				(pts
					(xy 281.432 -75.692) (xy 281.813 -75.692) (xy 281.813 -76.2) (xy 281.432 -76.2)
				)
			)
		)
		(zone
			(layer "F.Cu")
			(hatch none 0.5)
			(connect_pads
				(clearance 0)
			)
			(min_thickness 0.25)
			(keepout
				(tracks not_allowed)
				(vias allowed)
				(pads allowed)
				(copperpour not_allowed)
				(footprints allowed)
			)
			(placement
				(enabled no)
				(sheetname "")
			)
			(fill
				(thermal_gap 0.5)
				(thermal_bridge_width 0.5)
				(island_removal_mode 0)
			)
			(polygon
				(pts
					(xy 281.432 -75.692) (xy 281.813 -75.692) (xy 281.813 -76.2) (xy 281.432 -76.2)
				)
			)
		)
	)
	(footprint ""
		(layer "F.Cu")
		(at 261.942072 -77.636116)
		(property "Reference" "C5D27"
			(at 0 0 0)
			(layer "F.SilkS")
			(hide yes)
			(effects
				(font
					(size 1.27 1.27)
				)
			)
		)
		(property "Value" ""
			(at 0 0 0)
			(layer "F.Fab")
			(effects
				(font
					(size 1.27 1.27)
				)
			)
		)
		(duplicate_pad_numbers_are_jumpers no)
		(fp_poly
			(pts
				(xy -0.4953 -0.2032) (xy 0.4953 -0.2032) (xy 0.4953 1.6002) (xy -0.4953 1.6002)
			)
			(stroke
				(width 0)
				(type default)
			)
			(fill no)
			(layer "F.CrtYd")
		)
		(fp_line
			(start -0.4953 -0.2032)
			(end 0.4953 -0.2032)
			(stroke
				(width 0.1)
				(type default)
			)
			(layer "F.Fab")
		)
		(fp_line
			(start -0.4953 1.6002)
			(end -0.4953 -0.2032)
			(stroke
				(width 0.1)
				(type default)
			)
			(layer "F.Fab")
		)
		(fp_line
			(start 0.4953 -0.2032)
			(end 0.4953 1.6002)
			(stroke
				(width 0.1)
				(type default)
			)
			(layer "F.Fab")
		)
		(fp_line
			(start 0.4953 1.6002)
			(end -0.4953 1.6002)
			(stroke
				(width 0.1)
				(type default)
			)
			(layer "F.Fab")
		)
		(pad "1" smd rect
			(at 0 0)
			(size 0.762 0.889)
			(layers "F.Cu" "F.Mask" "F.Paste")
			(net "PVCCIN_CPU0")
		)
		(pad "2" smd rect
			(at 0 1.397)
			(size 0.762 0.889)
			(layers "F.Cu" "F.Mask" "F.Paste")
			(net "GND")
		)
		(zone
			(layer "F.Cu")
			(hatch none 0.5)
			(connect_pads
				(clearance 0)
			)
			(min_thickness 0.25)
			(keepout
				(tracks not_allowed)
				(vias allowed)
				(pads allowed)
				(copperpour not_allowed)
				(footprints allowed)
			)
			(placement
				(enabled no)
				(sheetname "")
			)
			(fill
				(thermal_gap 0.5)
				(thermal_bridge_width 0.5)
				(island_removal_mode 0)
			)
			(polygon
				(pts
					(xy 261.561072 -77.191616) (xy 262.323072 -77.191616) (xy 262.323072 -76.683616) (xy 261.561072 -76.683616)
				)
			)
		)
	)
	(footprint ""
		(layer "F.Cu")
		(at 163.576 -81.788 -90)
		(property "Reference" "R4D16"
			(at 0 0 270)
			(layer "F.SilkS")
			(hide yes)
			(effects
				(font
					(size 1.27 1.27)
				)
			)
		)
		(property "Value" ""
			(at 0 0 270)
			(layer "F.Fab")
			(effects
				(font
					(size 1.27 1.27)
				)
			)
		)
		(duplicate_pad_numbers_are_jumpers no)
		(fp_poly
			(pts
				(xy -0.2794 -0.1016) (xy 0.2794 -0.1016) (xy 0.2794 0.9906) (xy -0.2794 0.9906)
			)
			(stroke
				(width 0)
				(type default)
			)
			(fill no)
			(layer "F.CrtYd")
		)
		(fp_line
			(start -0.2794 0.9906)
			(end 0.2794 0.9906)
			(stroke
				(width 0.1)
				(type default)
			)
			(layer "F.Fab")
		)
		(fp_line
			(start 0.2794 0.9906)
			(end 0.2794 -0.1016)
			(stroke
				(width 0.1)
				(type default)
			)
			(layer "F.Fab")
		)
		(fp_line
			(start -0.2794 -0.1016)
			(end -0.2794 0.9906)
			(stroke
				(width 0.1)
				(type default)
			)
			(layer "F.Fab")
		)
		(fp_line
			(start 0.2794 -0.1016)
			(end -0.2794 -0.1016)
			(stroke
				(width 0.1)
				(type default)
			)
			(layer "F.Fab")
		)
		(pad "1" smd rect
			(at 0 0 270)
			(size 0.508 0.508)
			(layers "F.Cu" "F.Mask" "F.Paste")
			(net "CLK_100M_CPU1_PE_REFCLK_R_DN")
		)
		(pad "2" smd rect
			(at 0 0.889 270)
			(size 0.508 0.508)
			(layers "F.Cu" "F.Mask" "F.Paste")
			(net "CLK_100M_CPU1_PE_REFCLK_DN")
		)
		(zone
			(layer "F.Cu")
			(hatch none 0.5)
			(connect_pads
				(clearance 0)
			)
			(min_thickness 0.25)
			(keepout
				(tracks not_allowed)
				(vias allowed)
				(pads allowed)
				(copperpour not_allowed)
				(footprints allowed)
			)
			(placement
				(enabled no)
				(sheetname "")
			)
			(fill
				(thermal_gap 0.5)
				(thermal_bridge_width 0.5)
				(island_removal_mode 0)
			)
			(polygon
				(pts
					(xy 162.941 -82.042) (xy 162.941 -81.534) (xy 163.322 -81.534) (xy 163.322 -82.042)
				)
			)
		)
		(zone
			(layer "F.Cu")
			(hatch none 0.5)
			(connect_pads
				(clearance 0)
			)
			(min_thickness 0.25)
			(keepout
				(tracks allowed)
				(vias not_allowed)
				(pads allowed)
				(copperpour not_allowed)
				(footprints allowed)
			)
			(placement
				(enabled no)
				(sheetname "")
			)
			(fill
				(thermal_gap 0.5)
				(thermal_bridge_width 0.5)
				(island_removal_mode 0)
			)
			(polygon
				(pts
					(xy 163.322 -82.042) (xy 163.322 -81.534) (xy 162.941 -81.534) (xy 162.941 -82.042)
				)
			)
		)
	)
)
